(kicad_pcb
	(version 20260206)
	(generator "pcbnew")
	(generator_version "10.0")
	(general
		(thickness 1.6)
		(legacy_teardrops no)
	)
	(paper "A4")
	(title_block
		(title "04192023_DAF0TMB3IC0_F0TG_MB_C_brd_V02_OCP.brd")
		(comment 1 "Grand Teton / footprints 5993-5999 of 8354")
	)
	(layers
		(0 "F.Cu" signal "TOP")
		(4 "In1.Cu" signal "GND")
		(6 "In2.Cu" signal "IN1")
		(8 "In3.Cu" signal "GND1")
		(10 "In4.Cu" signal "IN2")
		(12 "In5.Cu" signal "GND2")
		(14 "In6.Cu" signal "IN3")
		(16 "In7.Cu" signal "GND3")
		(18 "In8.Cu" signal "VCC")
		(20 "In9.Cu" signal "VCC1")
		(22 "In10.Cu" signal "GND4")
		(24 "In11.Cu" signal "IN4")
		(26 "In12.Cu" signal "GND5")
		(28 "In13.Cu" signal "IN5")
		(30 "In14.Cu" signal "GND6")
		(32 "In15.Cu" signal "IN6")
		(34 "In16.Cu" signal "GND7")
		(2 "B.Cu" signal "BOTTOM")
		(9 "F.Adhes" user "F.Adhesive")
		(11 "B.Adhes" user "B.Adhesive")
		(13 "F.Paste" user "Package Geometry/Pastemask Top")
		(15 "B.Paste" user "Package Geometry/Pastemask Bottom")
		(5 "F.SilkS" user "Ref Des/Silkscreen Top")
		(7 "B.SilkS" user "Ref Des/Silkscreen Bottom")
		(1 "F.Mask" user "Board Geometry/Soldermask Top")
		(3 "B.Mask" user "Board Geometry/Soldermask Bottom")
		(17 "Dwgs.User" user "User.Drawings")
		(19 "Cmts.User" user "User.Comments")
		(21 "Eco1.User" user "User.Eco1")
		(23 "Eco2.User" user "User.Eco2")
		(25 "Edge.Cuts" user "Board Geometry/Outline")
		(27 "Margin" user)
		(31 "F.CrtYd" user "Package Geometry/Place Bound Top")
		(29 "B.CrtYd" user "Package Geometry/Place Bound Bottom")
		(35 "F.Fab" user "Ref Des/Assembly Top")
		(33 "B.Fab" user "Ref Des/Assembly Bottom")
	)
	(footprint ""
		(layer "B.Cu")
		(at 278.671782 -346.784168 90)
		(property "Reference" "PC185_4"
			(at 0 0 90)
			(layer "B.SilkS")
			(hide yes)
			(effects
				(font
					(size 1.27 1.27)
				)
				(justify mirror)
			)
		)
		(property "Value" ""
			(at 0 0 90)
			(layer "B.Fab")
			(effects
				(font
					(size 1.27 1.27)
				)
				(justify mirror)
			)
		)
		(duplicate_pad_numbers_are_jumpers no)
		(fp_line
			(start 1.524 -0.762)
			(end -1.524 -0.762)
			(stroke
				(width 0.1524)
				(type default)
			)
			(layer "B.SilkS")
		)
		(fp_line
			(start -1.524 -0.762)
			(end -1.524 0.762)
			(stroke
				(width 0.1524)
				(type default)
			)
			(layer "B.SilkS")
		)
		(fp_line
			(start 1.524 0.762)
			(end 1.524 -0.762)
			(stroke
				(width 0.1524)
				(type default)
			)
			(layer "B.SilkS")
		)
		(fp_line
			(start -1.524 0.762)
			(end 1.524 0.762)
			(stroke
				(width 0.1524)
				(type default)
			)
			(layer "B.SilkS")
		)
		(fp_line
			(start 1.1049 -0.724916)
			(end 1.1049 0.724916)
			(stroke
				(width 0.1)
				(type default)
			)
			(layer "B.Fab")
		)
		(fp_line
			(start -1.1049 -0.724916)
			(end 1.1049 -0.724916)
			(stroke
				(width 0.1)
				(type default)
			)
			(layer "B.Fab")
		)
		(fp_line
			(start 1.1049 0.724916)
			(end -1.1049 0.724916)
			(stroke
				(width 0.1)
				(type default)
			)
			(layer "B.Fab")
		)
		(fp_line
			(start -1.1049 0.724916)
			(end -1.1049 -0.724916)
			(stroke
				(width 0.1)
				(type default)
			)
			(layer "B.Fab")
		)
		(pad "1" smd rect
			(at 0.889 0 90)
			(size 1.016 1.27)
			(layers "B.Cu" "B.Mask" "B.Paste")
			(net "SW_P12V_AUX_PVDDIO_P0_FLT")
		)
		(pad "2" smd rect
			(at -0.889 0 90)
			(size 1.016 1.27)
			(layers "B.Cu" "B.Mask" "B.Paste")
			(net "GND")
		)
	)
	(footprint ""
		(layer "B.Cu")
		(at 148.252434 -203.704952 -90)
		(property "Reference" "C235"
			(at 0 0 90)
			(layer "B.SilkS")
			(hide yes)
			(effects
				(font
					(size 1.27 1.27)
				)
				(justify mirror)
			)
		)
		(property "Value" ""
			(at 0 0 90)
			(layer "B.Fab")
			(effects
				(font
					(size 1.27 1.27)
				)
				(justify mirror)
			)
		)
		(duplicate_pad_numbers_are_jumpers no)
		(fp_line
			(start -0.7874 0.4064)
			(end 0.7874 0.4064)
			(stroke
				(width 0.1524)
				(type default)
			)
			(layer "B.SilkS")
		)
		(fp_line
			(start 0.7874 0.4064)
			(end 0.7874 -0.4064)
			(stroke
				(width 0.1524)
				(type default)
			)
			(layer "B.SilkS")
		)
		(fp_line
			(start -0.7874 -0.4064)
			(end -0.7874 0.4064)
			(stroke
				(width 0.1524)
				(type default)
			)
			(layer "B.SilkS")
		)
		(fp_line
			(start 0.7874 -0.4064)
			(end -0.7874 -0.4064)
			(stroke
				(width 0.1524)
				(type default)
			)
			(layer "B.SilkS")
		)
		(fp_line
			(start -0.67945 0.3048)
			(end -0.120396 0.3048)
			(stroke
				(width 0.1)
				(type default)
			)
			(layer "B.Fab")
		)
		(fp_line
			(start -0.120396 0.3048)
			(end -0.120396 0.2794)
			(stroke
				(width 0.1)
				(type default)
			)
			(layer "B.Fab")
		)
		(fp_line
			(start 0.12065 0.3048)
			(end 0.67945 0.3048)
			(stroke
				(width 0.1)
				(type default)
			)
			(layer "B.Fab")
		)
		(fp_line
			(start 0.67945 0.3048)
			(end 0.67945 -0.305054)
			(stroke
				(width 0.1)
				(type default)
			)
			(layer "B.Fab")
		)
		(fp_line
			(start -0.120396 0.2794)
			(end 0.12065 0.2794)
			(stroke
				(width 0.1)
				(type default)
			)
			(layer "B.Fab")
		)
		(fp_line
			(start 0.12065 0.2794)
			(end 0.12065 0.3048)
			(stroke
				(width 0.1)
				(type default)
			)
			(layer "B.Fab")
		)
		(fp_line
			(start -0.12065 -0.2794)
			(end -0.12065 -0.3048)
			(stroke
				(width 0.1)
				(type default)
			)
			(layer "B.Fab")
		)
		(fp_line
			(start 0.12065 -0.2794)
			(end -0.12065 -0.2794)
			(stroke
				(width 0.1)
				(type default)
			)
			(layer "B.Fab")
		)
		(fp_line
			(start -0.67945 -0.3048)
			(end -0.67945 0.3048)
			(stroke
				(width 0.1)
				(type default)
			)
			(layer "B.Fab")
		)
		(fp_line
			(start -0.12065 -0.3048)
			(end -0.67945 -0.3048)
			(stroke
				(width 0.1)
				(type default)
			)
			(layer "B.Fab")
		)
		(fp_line
			(start 0.12065 -0.305054)
			(end 0.12065 -0.2794)
			(stroke
				(width 0.1)
				(type default)
			)
			(layer "B.Fab")
		)
		(fp_line
			(start 0.67945 -0.305054)
			(end 0.12065 -0.305054)
			(stroke
				(width 0.1)
				(type default)
			)
			(layer "B.Fab")
		)
		(pad "1" smd circle
			(at 0.40005 0 90)
			(size 0 0)
			(layers "B.Cu" "B.Mask" "B.Paste")
			(net "JTAG_CPU1_DBREQ_N")
		)
		(pad "2" smd circle
			(at -0.40005 0 90)
			(size 0 0)
			(layers "B.Cu" "B.Mask" "B.Paste")
			(net "GND")
		)
	)
	(footprint ""
		(layer "B.Cu")
		(at 327.216008 -203.529946)
		(property "Reference" "R157"
			(at 0 0 0)
			(layer "B.SilkS")
			(hide yes)
			(effects
				(font
					(size 1.27 1.27)
				)
				(justify mirror)
			)
		)
		(property "Value" ""
			(at 0 0 0)
			(layer "B.Fab")
			(effects
				(font
					(size 1.27 1.27)
				)
				(justify mirror)
			)
		)
		(duplicate_pad_numbers_are_jumpers no)
		(fp_line
			(start -0.7874 -0.4064)
			(end -0.7874 0.4064)
			(stroke
				(width 0.1524)
				(type default)
			)
			(layer "B.SilkS")
		)
		(fp_line
			(start -0.7874 0.4064)
			(end 0.7874 0.4064)
			(stroke
				(width 0.1524)
				(type default)
			)
			(layer "B.SilkS")
		)
		(fp_line
			(start 0.7874 -0.4064)
			(end -0.7874 -0.4064)
			(stroke
				(width 0.1524)
				(type default)
			)
			(layer "B.SilkS")
		)
		(fp_line
			(start 0.7874 0.4064)
			(end 0.7874 -0.4064)
			(stroke
				(width 0.1524)
				(type default)
			)
			(layer "B.SilkS")
		)
		(fp_line
			(start -0.67945 -0.3048)
			(end -0.67945 0.3048)
			(stroke
				(width 0.1)
				(type default)
			)
			(layer "B.Fab")
		)
		(fp_line
			(start -0.67945 0.3048)
			(end -0.120396 0.3048)
			(stroke
				(width 0.1)
				(type default)
			)
			(layer "B.Fab")
		)
		(fp_line
			(start -0.12065 -0.3048)
			(end -0.67945 -0.3048)
			(stroke
				(width 0.1)
				(type default)
			)
			(layer "B.Fab")
		)
		(fp_line
			(start -0.12065 -0.2794)
			(end -0.12065 -0.3048)
			(stroke
				(width 0.1)
				(type default)
			)
			(layer "B.Fab")
		)
		(fp_line
			(start -0.120396 0.2794)
			(end 0.12065 0.2794)
			(stroke
				(width 0.1)
				(type default)
			)
			(layer "B.Fab")
		)
		(fp_line
			(start -0.120396 0.3048)
			(end -0.120396 0.2794)
			(stroke
				(width 0.1)
				(type default)
			)
			(layer "B.Fab")
		)
		(fp_line
			(start 0.12065 -0.305054)
			(end 0.12065 -0.2794)
			(stroke
				(width 0.1)
				(type default)
			)
			(layer "B.Fab")
		)
		(fp_line
			(start 0.12065 -0.2794)
			(end -0.12065 -0.2794)
			(stroke
				(width 0.1)
				(type default)
			)
			(layer "B.Fab")
		)
		(fp_line
			(start 0.12065 0.2794)
			(end 0.12065 0.3048)
			(stroke
				(width 0.1)
				(type default)
			)
			(layer "B.Fab")
		)
		(fp_line
			(start 0.12065 0.3048)
			(end 0.67945 0.3048)
			(stroke
				(width 0.1)
				(type default)
			)
			(layer "B.Fab")
		)
		(fp_line
			(start 0.67945 -0.305054)
			(end 0.12065 -0.305054)
			(stroke
				(width 0.1)
				(type default)
			)
			(layer "B.Fab")
		)
		(fp_line
			(start 0.67945 0.3048)
			(end 0.67945 -0.305054)
			(stroke
				(width 0.1)
				(type default)
			)
			(layer "B.Fab")
		)
		(pad "1" smd circle
			(at 0.40005 0 180)
			(size 0 0)
			(layers "B.Cu" "B.Mask" "B.Paste")
			(net "CPU0_XTRIG_R2_L5")
		)
		(pad "2" smd circle
			(at -0.40005 0 180)
			(size 0 0)
			(layers "B.Cu" "B.Mask" "B.Paste")
			(net "CPU0_XTRIG_L5")
		)
	)
	(footprint ""
		(layer "B.Cu")
		(at 398.443958 -326.671432 180)
		(property "Reference" "R753"
			(at 0 0 0)
			(layer "B.SilkS")
			(hide yes)
			(effects
				(font
					(size 1.27 1.27)
				)
				(justify mirror)
			)
		)
		(property "Value" ""
			(at 0 0 0)
			(layer "B.Fab")
			(effects
				(font
					(size 1.27 1.27)
				)
				(justify mirror)
			)
		)
		(duplicate_pad_numbers_are_jumpers no)
		(fp_line
			(start 0.7874 0.4064)
			(end 0.7874 -0.4064)
			(stroke
				(width 0.1524)
				(type default)
			)
			(layer "B.SilkS")
		)
		(fp_line
			(start 0.7874 -0.4064)
			(end -0.7874 -0.4064)
			(stroke
				(width 0.1524)
				(type default)
			)
			(layer "B.SilkS")
		)
		(fp_line
			(start -0.7874 0.4064)
			(end 0.7874 0.4064)
			(stroke
				(width 0.1524)
				(type default)
			)
			(layer "B.SilkS")
		)
		(fp_line
			(start -0.7874 -0.4064)
			(end -0.7874 0.4064)
			(stroke
				(width 0.1524)
				(type default)
			)
			(layer "B.SilkS")
		)
		(fp_line
			(start 0.67945 0.3048)
			(end 0.67945 -0.305054)
			(stroke
				(width 0.1)
				(type default)
			)
			(layer "B.Fab")
		)
		(fp_line
			(start 0.67945 -0.305054)
			(end 0.12065 -0.305054)
			(stroke
				(width 0.1)
				(type default)
			)
			(layer "B.Fab")
		)
		(fp_line
			(start 0.12065 0.3048)
			(end 0.67945 0.3048)
			(stroke
				(width 0.1)
				(type default)
			)
			(layer "B.Fab")
		)
		(fp_line
			(start 0.12065 0.2794)
			(end 0.12065 0.3048)
			(stroke
				(width 0.1)
				(type default)
			)
			(layer "B.Fab")
		)
		(fp_line
			(start 0.12065 -0.2794)
			(end -0.12065 -0.2794)
			(stroke
				(width 0.1)
				(type default)
			)
			(layer "B.Fab")
		)
		(fp_line
			(start 0.12065 -0.305054)
			(end 0.12065 -0.2794)
			(stroke
				(width 0.1)
				(type default)
			)
			(layer "B.Fab")
		)
		(fp_line
			(start -0.120396 0.3048)
			(end -0.120396 0.2794)
			(stroke
				(width 0.1)
				(type default)
			)
			(layer "B.Fab")
		)
		(fp_line
			(start -0.120396 0.2794)
			(end 0.12065 0.2794)
			(stroke
				(width 0.1)
				(type default)
			)
			(layer "B.Fab")
		)
		(fp_line
			(start -0.12065 -0.2794)
			(end -0.12065 -0.3048)
			(stroke
				(width 0.1)
				(type default)
			)
			(layer "B.Fab")
		)
		(fp_line
			(start -0.12065 -0.3048)
			(end -0.67945 -0.3048)
			(stroke
				(width 0.1)
				(type default)
			)
			(layer "B.Fab")
		)
		(fp_line
			(start -0.67945 0.3048)
			(end -0.120396 0.3048)
			(stroke
				(width 0.1)
				(type default)
			)
			(layer "B.Fab")
		)
		(fp_line
			(start -0.67945 -0.3048)
			(end -0.67945 0.3048)
			(stroke
				(width 0.1)
				(type default)
			)
			(layer "B.Fab")
		)
		(pad "1" smd circle
			(at 0.40005 0)
			(size 0 0)
			(layers "B.Cu" "B.Mask" "B.Paste")
			(net "GND")
		)
		(pad "2" smd circle
			(at -0.40005 0)
			(size 0 0)
			(layers "B.Cu" "B.Mask" "B.Paste")
			(net "PD_ESPI_CPU0_CLK2")
		)
	)
	(footprint ""
		(layer "B.Cu")
		(at 85.852 -147.955)
		(property "Reference" "C297"
			(at 0 0 0)
			(layer "B.SilkS")
			(hide yes)
			(effects
				(font
					(size 1.27 1.27)
				)
				(justify mirror)
			)
		)
		(property "Value" ""
			(at 0 0 0)
			(layer "B.Fab")
			(effects
				(font
					(size 1.27 1.27)
				)
				(justify mirror)
			)
		)
		(duplicate_pad_numbers_are_jumpers no)
		(fp_line
			(start -0.7874 -0.4064)
			(end -0.7874 0.4064)
			(stroke
				(width 0.1524)
				(type default)
			)
			(layer "B.SilkS")
		)
		(fp_line
			(start -0.7874 0.4064)
			(end 0.7874 0.4064)
			(stroke
				(width 0.1524)
				(type default)
			)
			(layer "B.SilkS")
		)
		(fp_line
			(start 0.7874 -0.4064)
			(end -0.7874 -0.4064)
			(stroke
				(width 0.1524)
				(type default)
			)
			(layer "B.SilkS")
		)
		(fp_line
			(start 0.7874 0.4064)
			(end 0.7874 -0.4064)
			(stroke
				(width 0.1524)
				(type default)
			)
			(layer "B.SilkS")
		)
		(fp_line
			(start -0.67945 -0.3048)
			(end -0.67945 0.3048)
			(stroke
				(width 0.1)
				(type default)
			)
			(layer "B.Fab")
		)
		(fp_line
			(start -0.67945 0.3048)
			(end -0.120396 0.3048)
			(stroke
				(width 0.1)
				(type default)
			)
			(layer "B.Fab")
		)
		(fp_line
			(start -0.12065 -0.3048)
			(end -0.67945 -0.3048)
			(stroke
				(width 0.1)
				(type default)
			)
			(layer "B.Fab")
		)
		(fp_line
			(start -0.12065 -0.2794)
			(end -0.12065 -0.3048)
			(stroke
				(width 0.1)
				(type default)
			)
			(layer "B.Fab")
		)
		(fp_line
			(start -0.120396 0.2794)
			(end 0.12065 0.2794)
			(stroke
				(width 0.1)
				(type default)
			)
			(layer "B.Fab")
		)
		(fp_line
			(start -0.120396 0.3048)
			(end -0.120396 0.2794)
			(stroke
				(width 0.1)
				(type default)
			)
			(layer "B.Fab")
		)
		(fp_line
			(start 0.12065 -0.305054)
			(end 0.12065 -0.2794)
			(stroke
				(width 0.1)
				(type default)
			)
			(layer "B.Fab")
		)
		(fp_line
			(start 0.12065 -0.2794)
			(end -0.12065 -0.2794)
			(stroke
				(width 0.1)
				(type default)
			)
			(layer "B.Fab")
		)
		(fp_line
			(start 0.12065 0.2794)
			(end 0.12065 0.3048)
			(stroke
				(width 0.1)
				(type default)
			)
			(layer "B.Fab")
		)
		(fp_line
			(start 0.12065 0.3048)
			(end 0.67945 0.3048)
			(stroke
				(width 0.1)
				(type default)
			)
			(layer "B.Fab")
		)
		(fp_line
			(start 0.67945 -0.305054)
			(end 0.12065 -0.305054)
			(stroke
				(width 0.1)
				(type default)
			)
			(layer "B.Fab")
		)
		(fp_line
			(start 0.67945 0.3048)
			(end 0.67945 -0.305054)
			(stroke
				(width 0.1)
				(type default)
			)
			(layer "B.Fab")
		)
		(pad "1" smd circle
			(at 0.40005 0 180)
			(size 0 0)
			(layers "B.Cu" "B.Mask" "B.Paste")
			(net "SVID_PVDDCR_CPU0_P1_SVC_R")
		)
		(pad "2" smd circle
			(at -0.40005 0 180)
			(size 0 0)
			(layers "B.Cu" "B.Mask" "B.Paste")
			(net "GND")
		)
	)
	(footprint ""
		(layer "B.Cu")
		(at 164.403532 -434.15458 90)
		(property "Reference" "R4122"
			(at 0 0 90)
			(layer "B.SilkS")
			(hide yes)
			(effects
				(font
					(size 1.27 1.27)
				)
				(justify mirror)
			)
		)
		(property "Value" ""
			(at 0 0 90)
			(layer "B.Fab")
			(effects
				(font
					(size 1.27 1.27)
				)
				(justify mirror)
			)
		)
		(duplicate_pad_numbers_are_jumpers no)
		(fp_line
			(start 0.7874 -0.4064)
			(end -0.7874 -0.4064)
			(stroke
				(width 0.1524)
				(type default)
			)
			(layer "B.SilkS")
		)
		(fp_line
			(start -0.7874 -0.4064)
			(end -0.7874 0.4064)
			(stroke
				(width 0.1524)
				(type default)
			)
			(layer "B.SilkS")
		)
		(fp_line
			(start 0.7874 0.4064)
			(end 0.7874 -0.4064)
			(stroke
				(width 0.1524)
				(type default)
			)
			(layer "B.SilkS")
		)
		(fp_line
			(start -0.7874 0.4064)
			(end 0.7874 0.4064)
			(stroke
				(width 0.1524)
				(type default)
			)
			(layer "B.SilkS")
		)
		(fp_line
			(start 0.67945 -0.305054)
			(end 0.12065 -0.305054)
			(stroke
				(width 0.1)
				(type default)
			)
			(layer "B.Fab")
		)
		(fp_line
			(start 0.12065 -0.305054)
			(end 0.12065 -0.2794)
			(stroke
				(width 0.1)
				(type default)
			)
			(layer "B.Fab")
		)
		(fp_line
			(start -0.12065 -0.3048)
			(end -0.67945 -0.3048)
			(stroke
				(width 0.1)
				(type default)
			)
			(layer "B.Fab")
		)
		(fp_line
			(start -0.67945 -0.3048)
			(end -0.67945 0.3048)
			(stroke
				(width 0.1)
				(type default)
			)
			(layer "B.Fab")
		)
		(fp_line
			(start 0.12065 -0.2794)
			(end -0.12065 -0.2794)
			(stroke
				(width 0.1)
				(type default)
			)
			(layer "B.Fab")
		)
		(fp_line
			(start -0.12065 -0.2794)
			(end -0.12065 -0.3048)
			(stroke
				(width 0.1)
				(type default)
			)
			(layer "B.Fab")
		)
		(fp_line
			(start 0.12065 0.2794)
			(end 0.12065 0.3048)
			(stroke
				(width 0.1)
				(type default)
			)
			(layer "B.Fab")
		)
		(fp_line
			(start -0.120396 0.2794)
			(end 0.12065 0.2794)
			(stroke
				(width 0.1)
				(type default)
			)
			(layer "B.Fab")
		)
		(fp_line
			(start 0.67945 0.3048)
			(end 0.67945 -0.305054)
			(stroke
				(width 0.1)
				(type default)
			)
			(layer "B.Fab")
		)
		(fp_line
			(start 0.12065 0.3048)
			(end 0.67945 0.3048)
			(stroke
				(width 0.1)
				(type default)
			)
			(layer "B.Fab")
		)
		(fp_line
			(start -0.120396 0.3048)
			(end -0.120396 0.2794)
			(stroke
				(width 0.1)
				(type default)
			)
			(layer "B.Fab")
		)
		(fp_line
			(start -0.67945 0.3048)
			(end -0.120396 0.3048)
			(stroke
				(width 0.1)
				(type default)
			)
			(layer "B.Fab")
		)
		(pad "1" smd circle
			(at 0.40005 0 270)
			(size 0 0)
			(layers "B.Cu" "B.Mask" "B.Paste")
			(net "PRSNT_CABLE_GPU_B3_N")
		)
		(pad "2" smd circle
			(at -0.40005 0 270)
			(size 0 0)
			(layers "B.Cu" "B.Mask" "B.Paste")
			(net "GND")
		)
	)
	(footprint ""
		(layer "B.Cu")
		(at 421.146224 -396.393162 -90)
		(property "Reference" "C790"
			(at 0 0 90)
			(layer "B.SilkS")
			(hide yes)
			(effects
				(font
					(size 1.27 1.27)
				)
				(justify mirror)
			)
		)
		(property "Value" ""
			(at 0 0 90)
			(layer "B.Fab")
			(effects
				(font
					(size 1.27 1.27)
				)
				(justify mirror)
			)
		)
		(duplicate_pad_numbers_are_jumpers no)
		(fp_line
			(start -0.299974 0.150114)
			(end 0.299974 0.150114)
			(stroke
				(width 0.1)
				(type default)
			)
			(layer "B.Fab")
		)
		(fp_line
			(start 0.299974 0.150114)
			(end 0.299974 -0.150114)
			(stroke
				(width 0.1)
				(type default)
			)
			(layer "B.Fab")
		)
		(fp_line
			(start -0.299974 -0.150114)
			(end -0.299974 0.150114)
			(stroke
				(width 0.1)
				(type default)
			)
			(layer "B.Fab")
		)
		(fp_line
			(start 0.299974 -0.150114)
			(end -0.299974 -0.150114)
			(stroke
				(width 0.1)
				(type default)
			)
			(layer "B.Fab")
		)
		(pad "1" smd rect
			(at 0.2667 0 90)
			(size 0.3048 0.381)
			(layers "B.Cu" "B.Mask" "B.Paste")
			(net "P0V9_CPU0_RT2_2A")
		)
		(pad "2" smd rect
			(at -0.2667 0 90)
			(size 0.3048 0.381)
			(layers "B.Cu" "B.Mask" "B.Paste")
			(net "GND")
		)
	)
)
